(kicad_pcb
	(version 20241229)
	(generator "pcbnew")
	(generator_version "9.0")
	(general
		(thickness 1.6)
		(legacy_teardrops no)
	)
	(paper "A4")
	(title_block
		(title "environment-sensor")
		(comment 1 "footprints 109-109 of 109")
	)
	(layers
		(0 "F.Cu" signal)
		(4 "In1.Cu" signal)
		(6 "In2.Cu" signal)
		(2 "B.Cu" signal)
		(9 "F.Adhes" user "F.Adhesive")
		(11 "B.Adhes" user "B.Adhesive")
		(13 "F.Paste" user)
		(15 "B.Paste" user)
		(5 "F.SilkS" user "F.Silkscreen")
		(7 "B.SilkS" user "B.Silkscreen")
		(1 "F.Mask" user)
		(3 "B.Mask" user)
		(17 "Dwgs.User" user "User.Drawings")
		(19 "Cmts.User" user "User.Comments")
		(21 "Eco1.User" user "User.Eco1")
		(23 "Eco2.User" user "User.Eco2")
		(25 "Edge.Cuts" user)
		(27 "Margin" user)
		(31 "F.CrtYd" user "F.Courtyard")
		(29 "B.CrtYd" user "B.Courtyard")
		(35 "F.Fab" user)
		(33 "B.Fab" user)
	)
	(footprint "antmicro-footprints:antmicro-logo_scaled_12mm"
		(layer "B.Cu")
		(at 170 120.2 -90)
		(property "Reference" "N1"
			(at 0 1.5 90)
			(layer "B.SilkS")
			(hide yes)
			(effects
				(font
					(size 0.7 0.7)
					(thickness 0.15)
				)
				(justify left bottom mirror)
			)
		)
		(property "Value" "antmicro_logo"
			(at 0 -2 90)
			(layer "B.SilkS")
			(hide yes)
			(effects
				(font
					(size 0.7 0.7)
					(thickness 0.15)
				)
				(justify left bottom mirror)
			)
		)
		(property "Description" "Mechanical part"
			(at 0 0 270)
			(layer "F.Fab")
			(hide yes)
			(effects
				(font
					(size 1.27 1.27)
					(thickness 0.15)
				)
			)
		)
		(property "Author" "Antmicro"
			(at 49.8 290.2 0)
			(layer "B.Fab")
			(hide yes)
			(effects
				(font
					(size 1 1)
					(thickness 0.15)
				)
				(justify mirror)
			)
		)
		(property "License" "Apache-2.0"
			(at 49.8 290.2 0)
			(layer "B.Fab")
			(hide yes)
			(effects
				(font
					(size 1 1)
					(thickness 0.15)
				)
				(justify mirror)
			)
		)
		(property "MPN" ""
			(at 49.8 290.2 0)
			(layer "B.Fab")
			(hide yes)
			(effects
				(font
					(size 1 1)
					(thickness 0.15)
				)
				(justify mirror)
			)
		)
		(property "Manufacturer" ""
			(at 49.8 290.2 0)
			(layer "B.Fab")
			(hide yes)
			(effects
				(font
					(size 1 1)
					(thickness 0.15)
				)
				(justify mirror)
			)
		)
		(property "Public" "False"
			(at 49.8 290.2 0)
			(layer "B.Fab")
			(hide yes)
			(effects
				(font
					(size 1 1)
					(thickness 0.15)
				)
				(justify mirror)
			)
		)
		(sheetfile "environment-sensor.kicad_sch")
		(attr exclude_from_bom allow_soldermask_bridges)
	)
)
